(kicad_pcb
	(version 20260206)
	(generator "pcbnew")
	(generator_version "10.0")
	(general
		(thickness 1.6)
		(legacy_teardrops no)
	)
	(paper "A4")
	(title_block
		(title "01162023_DA0F0TEBIF0_F0T_Expander_BD_F_brd_V02_OCP.brd")
		(comment 1 "Grand Teton / footprints 4316-4321 of 9728")
	)
	(layers
		(0 "F.Cu" signal "TOP")
		(4 "In1.Cu" signal "GND")
		(6 "In2.Cu" signal "VCC")
		(8 "In3.Cu" signal "VCC1")
		(10 "In4.Cu" signal "GND1")
		(12 "In5.Cu" signal "IN1")
		(14 "In6.Cu" signal "GND2")
		(16 "In7.Cu" signal "IN2")
		(18 "In8.Cu" signal "GND3")
		(20 "In9.Cu" signal "IN3")
		(22 "In10.Cu" signal "GND4")
		(24 "In11.Cu" signal "IN4")
		(26 "In12.Cu" signal "GND5")
		(28 "In13.Cu" signal "IN5")
		(30 "In14.Cu" signal "GND6")
		(32 "In15.Cu" signal "IN6")
		(34 "In16.Cu" signal "GND7")
		(2 "B.Cu" signal "BOTTOM")
		(9 "F.Adhes" user "F.Adhesive")
		(11 "B.Adhes" user "B.Adhesive")
		(13 "F.Paste" user "Package Geometry/Pastemask Top")
		(15 "B.Paste" user "Package Geometry/Pastemask Bottom")
		(5 "F.SilkS" user "Ref Des/Silkscreen Top")
		(7 "B.SilkS" user "Ref Des/Silkscreen Bottom")
		(1 "F.Mask" user "Board Geometry/Soldermask Top")
		(3 "B.Mask" user "Board Geometry/Soldermask Bottom")
		(17 "Dwgs.User" user "User.Drawings")
		(19 "Cmts.User" user "User.Comments")
		(21 "Eco1.User" user "User.Eco1")
		(23 "Eco2.User" user "User.Eco2")
		(25 "Edge.Cuts" user "Board Geometry/Outline")
		(27 "Margin" user)
		(31 "F.CrtYd" user "Package Geometry/Place Bound Top")
		(29 "B.CrtYd" user "Package Geometry/Place Bound Bottom")
		(35 "F.Fab" user "Ref Des/Assembly Top")
		(33 "B.Fab" user "Ref Des/Assembly Bottom")
	)
	(footprint ""
		(layer "F.Cu")
		(at 172.473874 -27.006296 -90)
		(property "Reference" "PC934"
			(at 0 0 270)
			(layer "F.SilkS")
			(hide yes)
			(effects
				(font
					(size 1.27 1.27)
				)
			)
		)
		(property "Value" ""
			(at 0 0 270)
			(layer "F.Fab")
			(effects
				(font
					(size 1.27 1.27)
				)
			)
		)
		(duplicate_pad_numbers_are_jumpers no)
		(fp_line
			(start -0.7874 0.4064)
			(end -0.7874 -0.4064)
			(stroke
				(width 0.1524)
				(type default)
			)
			(layer "F.SilkS")
		)
		(fp_line
			(start 0.7874 0.4064)
			(end -0.7874 0.4064)
			(stroke
				(width 0.1524)
				(type default)
			)
			(layer "F.SilkS")
		)
		(fp_line
			(start -0.7874 -0.4064)
			(end 0.7874 -0.4064)
			(stroke
				(width 0.1524)
				(type default)
			)
			(layer "F.SilkS")
		)
		(fp_line
			(start 0.7874 -0.4064)
			(end 0.7874 0.4064)
			(stroke
				(width 0.1524)
				(type default)
			)
			(layer "F.SilkS")
		)
		(fp_line
			(start -0.67945 0.3048)
			(end -0.67945 -0.305054)
			(stroke
				(width 0.1)
				(type default)
			)
			(layer "F.Fab")
		)
		(fp_line
			(start -0.12065 0.3048)
			(end -0.67945 0.3048)
			(stroke
				(width 0.1)
				(type default)
			)
			(layer "F.Fab")
		)
		(fp_line
			(start 0.120396 0.3048)
			(end 0.120396 0.2794)
			(stroke
				(width 0.1)
				(type default)
			)
			(layer "F.Fab")
		)
		(fp_line
			(start 0.67945 0.3048)
			(end 0.120396 0.3048)
			(stroke
				(width 0.1)
				(type default)
			)
			(layer "F.Fab")
		)
		(fp_line
			(start -0.12065 0.2794)
			(end -0.12065 0.3048)
			(stroke
				(width 0.1)
				(type default)
			)
			(layer "F.Fab")
		)
		(fp_line
			(start 0.120396 0.2794)
			(end -0.12065 0.2794)
			(stroke
				(width 0.1)
				(type default)
			)
			(layer "F.Fab")
		)
		(fp_line
			(start -0.12065 -0.2794)
			(end 0.12065 -0.2794)
			(stroke
				(width 0.1)
				(type default)
			)
			(layer "F.Fab")
		)
		(fp_line
			(start 0.12065 -0.2794)
			(end 0.12065 -0.3048)
			(stroke
				(width 0.1)
				(type default)
			)
			(layer "F.Fab")
		)
		(fp_line
			(start 0.12065 -0.3048)
			(end 0.67945 -0.3048)
			(stroke
				(width 0.1)
				(type default)
			)
			(layer "F.Fab")
		)
		(fp_line
			(start 0.67945 -0.3048)
			(end 0.67945 0.3048)
			(stroke
				(width 0.1)
				(type default)
			)
			(layer "F.Fab")
		)
		(fp_line
			(start -0.67945 -0.305054)
			(end -0.12065 -0.305054)
			(stroke
				(width 0.1)
				(type default)
			)
			(layer "F.Fab")
		)
		(fp_line
			(start -0.12065 -0.305054)
			(end -0.12065 -0.2794)
			(stroke
				(width 0.1)
				(type default)
			)
			(layer "F.Fab")
		)
		(pad "1" smd circle
			(at -0.40005 0 270)
			(size 0 0)
			(layers "F.Cu" "F.Mask" "F.Paste")
			(net "P3V3_SSD6_CO_MODE")
		)
		(pad "2" smd circle
			(at 0.40005 0 270)
			(size 0 0)
			(layers "F.Cu" "F.Mask" "F.Paste")
			(net "GND")
		)
	)
	(footprint ""
		(layer "F.Cu")
		(at 398.41551 -42.853102 180)
		(property "Reference" "R5905"
			(at 0 0 180)
			(layer "F.SilkS")
			(hide yes)
			(effects
				(font
					(size 1.27 1.27)
				)
			)
		)
		(property "Value" ""
			(at 0 0 180)
			(layer "F.Fab")
			(effects
				(font
					(size 1.27 1.27)
				)
			)
		)
		(duplicate_pad_numbers_are_jumpers no)
		(fp_line
			(start 0.7874 0.4064)
			(end -0.7874 0.4064)
			(stroke
				(width 0.1524)
				(type default)
			)
			(layer "F.SilkS")
		)
		(fp_line
			(start 0.7874 -0.4064)
			(end 0.7874 0.4064)
			(stroke
				(width 0.1524)
				(type default)
			)
			(layer "F.SilkS")
		)
		(fp_line
			(start -0.7874 0.4064)
			(end -0.7874 -0.4064)
			(stroke
				(width 0.1524)
				(type default)
			)
			(layer "F.SilkS")
		)
		(fp_line
			(start -0.7874 -0.4064)
			(end 0.7874 -0.4064)
			(stroke
				(width 0.1524)
				(type default)
			)
			(layer "F.SilkS")
		)
		(fp_line
			(start 0.67945 0.3048)
			(end 0.120396 0.3048)
			(stroke
				(width 0.1)
				(type default)
			)
			(layer "F.Fab")
		)
		(fp_line
			(start 0.67945 -0.3048)
			(end 0.67945 0.3048)
			(stroke
				(width 0.1)
				(type default)
			)
			(layer "F.Fab")
		)
		(fp_line
			(start 0.12065 -0.2794)
			(end 0.12065 -0.3048)
			(stroke
				(width 0.1)
				(type default)
			)
			(layer "F.Fab")
		)
		(fp_line
			(start 0.12065 -0.3048)
			(end 0.67945 -0.3048)
			(stroke
				(width 0.1)
				(type default)
			)
			(layer "F.Fab")
		)
		(fp_line
			(start 0.120396 0.3048)
			(end 0.120396 0.2794)
			(stroke
				(width 0.1)
				(type default)
			)
			(layer "F.Fab")
		)
		(fp_line
			(start 0.120396 0.2794)
			(end -0.12065 0.2794)
			(stroke
				(width 0.1)
				(type default)
			)
			(layer "F.Fab")
		)
		(fp_line
			(start -0.12065 0.3048)
			(end -0.67945 0.3048)
			(stroke
				(width 0.1)
				(type default)
			)
			(layer "F.Fab")
		)
		(fp_line
			(start -0.12065 0.2794)
			(end -0.12065 0.3048)
			(stroke
				(width 0.1)
				(type default)
			)
			(layer "F.Fab")
		)
		(fp_line
			(start -0.12065 -0.2794)
			(end 0.12065 -0.2794)
			(stroke
				(width 0.1)
				(type default)
			)
			(layer "F.Fab")
		)
		(fp_line
			(start -0.12065 -0.305054)
			(end -0.12065 -0.2794)
			(stroke
				(width 0.1)
				(type default)
			)
			(layer "F.Fab")
		)
		(fp_line
			(start -0.67945 0.3048)
			(end -0.67945 -0.305054)
			(stroke
				(width 0.1)
				(type default)
			)
			(layer "F.Fab")
		)
		(fp_line
			(start -0.67945 -0.305054)
			(end -0.12065 -0.305054)
			(stroke
				(width 0.1)
				(type default)
			)
			(layer "F.Fab")
		)
		(pad "1" smd circle
			(at -0.40005 0 180)
			(size 0 0)
			(layers "F.Cu" "F.Mask" "F.Paste")
			(net "SSD13_ADC_A1")
		)
		(pad "2" smd circle
			(at 0.40005 0 180)
			(size 0 0)
			(layers "F.Cu" "F.Mask" "F.Paste")
			(net "SMB_SSD13_ADC_SCL")
		)
	)
	(footprint ""
		(layer "F.Cu")
		(at 94.809056 -95.041466 -90)
		(property "Reference" "PC326"
			(at 0 0 270)
			(layer "F.SilkS")
			(hide yes)
			(effects
				(font
					(size 1.27 1.27)
				)
			)
		)
		(property "Value" ""
			(at 0 0 270)
			(layer "F.Fab")
			(effects
				(font
					(size 1.27 1.27)
				)
			)
		)
		(duplicate_pad_numbers_are_jumpers no)
		(fp_line
			(start -0.7874 0.4064)
			(end -0.7874 -0.4064)
			(stroke
				(width 0.1524)
				(type default)
			)
			(layer "F.SilkS")
		)
		(fp_line
			(start 0.7874 0.4064)
			(end -0.7874 0.4064)
			(stroke
				(width 0.1524)
				(type default)
			)
			(layer "F.SilkS")
		)
		(fp_line
			(start -0.7874 -0.4064)
			(end 0.7874 -0.4064)
			(stroke
				(width 0.1524)
				(type default)
			)
			(layer "F.SilkS")
		)
		(fp_line
			(start 0.7874 -0.4064)
			(end 0.7874 0.4064)
			(stroke
				(width 0.1524)
				(type default)
			)
			(layer "F.SilkS")
		)
		(fp_line
			(start -0.6858 0.3048)
			(end -0.6858 -0.3048)
			(stroke
				(width 0.1)
				(type default)
			)
			(layer "F.Fab")
		)
		(fp_line
			(start -0.1016 0.3048)
			(end -0.6858 0.3048)
			(stroke
				(width 0.1)
				(type default)
			)
			(layer "F.Fab")
		)
		(fp_line
			(start 0.1016 0.3048)
			(end 0.1016 0.2794)
			(stroke
				(width 0.1)
				(type default)
			)
			(layer "F.Fab")
		)
		(fp_line
			(start 0.6858 0.3048)
			(end 0.1016 0.3048)
			(stroke
				(width 0.1)
				(type default)
			)
			(layer "F.Fab")
		)
		(fp_line
			(start -0.1016 0.2794)
			(end -0.1016 0.3048)
			(stroke
				(width 0.1)
				(type default)
			)
			(layer "F.Fab")
		)
		(fp_line
			(start 0.1016 0.2794)
			(end -0.1016 0.2794)
			(stroke
				(width 0.1)
				(type default)
			)
			(layer "F.Fab")
		)
		(fp_line
			(start -0.1016 -0.2794)
			(end 0.1016 -0.2794)
			(stroke
				(width 0.1)
				(type default)
			)
			(layer "F.Fab")
		)
		(fp_line
			(start 0.1016 -0.2794)
			(end 0.1016 -0.3048)
			(stroke
				(width 0.1)
				(type default)
			)
			(layer "F.Fab")
		)
		(fp_line
			(start -0.6858 -0.3048)
			(end -0.1016 -0.3048)
			(stroke
				(width 0.1)
				(type default)
			)
			(layer "F.Fab")
		)
		(fp_line
			(start -0.1016 -0.3048)
			(end -0.1016 -0.2794)
			(stroke
				(width 0.1)
				(type default)
			)
			(layer "F.Fab")
		)
		(fp_line
			(start 0.1016 -0.3048)
			(end 0.6858 -0.3048)
			(stroke
				(width 0.1)
				(type default)
			)
			(layer "F.Fab")
		)
		(fp_line
			(start 0.6858 -0.3048)
			(end 0.6858 0.3048)
			(stroke
				(width 0.1)
				(type default)
			)
			(layer "F.Fab")
		)
		(pad "1" smd rect
			(at -0.40005 0 90)
			(size 0.4572 0.508)
			(layers "F.Cu" "F.Mask" "F.Paste")
			(net "P12V_NIC1_SS")
		)
		(pad "2" smd rect
			(at 0.40005 0 90)
			(size 0.4572 0.508)
			(layers "F.Cu" "F.Mask" "F.Paste")
			(net "GND")
		)
	)
	(footprint ""
		(layer "F.Cu")
		(at 31.656274 -61.487812 180)
		(property "Reference" "R5837"
			(at 0 0 180)
			(layer "F.SilkS")
			(hide yes)
			(effects
				(font
					(size 1.27 1.27)
				)
			)
		)
		(property "Value" ""
			(at 0 0 180)
			(layer "F.Fab")
			(effects
				(font
					(size 1.27 1.27)
				)
			)
		)
		(duplicate_pad_numbers_are_jumpers no)
		(fp_line
			(start 0.7874 0.4064)
			(end -0.7874 0.4064)
			(stroke
				(width 0.1524)
				(type default)
			)
			(layer "F.SilkS")
		)
		(fp_line
			(start 0.7874 -0.4064)
			(end 0.7874 0.4064)
			(stroke
				(width 0.1524)
				(type default)
			)
			(layer "F.SilkS")
		)
		(fp_line
			(start -0.7874 0.4064)
			(end -0.7874 -0.4064)
			(stroke
				(width 0.1524)
				(type default)
			)
			(layer "F.SilkS")
		)
		(fp_line
			(start -0.7874 -0.4064)
			(end 0.7874 -0.4064)
			(stroke
				(width 0.1524)
				(type default)
			)
			(layer "F.SilkS")
		)
		(fp_line
			(start 0.67945 0.3048)
			(end 0.120396 0.3048)
			(stroke
				(width 0.1)
				(type default)
			)
			(layer "F.Fab")
		)
		(fp_line
			(start 0.67945 -0.3048)
			(end 0.67945 0.3048)
			(stroke
				(width 0.1)
				(type default)
			)
			(layer "F.Fab")
		)
		(fp_line
			(start 0.12065 -0.2794)
			(end 0.12065 -0.3048)
			(stroke
				(width 0.1)
				(type default)
			)
			(layer "F.Fab")
		)
		(fp_line
			(start 0.12065 -0.3048)
			(end 0.67945 -0.3048)
			(stroke
				(width 0.1)
				(type default)
			)
			(layer "F.Fab")
		)
		(fp_line
			(start 0.120396 0.3048)
			(end 0.120396 0.2794)
			(stroke
				(width 0.1)
				(type default)
			)
			(layer "F.Fab")
		)
		(fp_line
			(start 0.120396 0.2794)
			(end -0.12065 0.2794)
			(stroke
				(width 0.1)
				(type default)
			)
			(layer "F.Fab")
		)
		(fp_line
			(start -0.12065 0.3048)
			(end -0.67945 0.3048)
			(stroke
				(width 0.1)
				(type default)
			)
			(layer "F.Fab")
		)
		(fp_line
			(start -0.12065 0.2794)
			(end -0.12065 0.3048)
			(stroke
				(width 0.1)
				(type default)
			)
			(layer "F.Fab")
		)
		(fp_line
			(start -0.12065 -0.2794)
			(end 0.12065 -0.2794)
			(stroke
				(width 0.1)
				(type default)
			)
			(layer "F.Fab")
		)
		(fp_line
			(start -0.12065 -0.305054)
			(end -0.12065 -0.2794)
			(stroke
				(width 0.1)
				(type default)
			)
			(layer "F.Fab")
		)
		(fp_line
			(start -0.67945 0.3048)
			(end -0.67945 -0.305054)
			(stroke
				(width 0.1)
				(type default)
			)
			(layer "F.Fab")
		)
		(fp_line
			(start -0.67945 -0.305054)
			(end -0.12065 -0.305054)
			(stroke
				(width 0.1)
				(type default)
			)
			(layer "F.Fab")
		)
		(pad "1" smd circle
			(at -0.40005 0 180)
			(size 0 0)
			(layers "F.Cu" "F.Mask" "F.Paste")
			(net "P3V3_AUX")
		)
		(pad "2" smd circle
			(at 0.40005 0 180)
			(size 0 0)
			(layers "F.Cu" "F.Mask" "F.Paste")
			(net "PWRGD_P12V_SSD1_D")
		)
	)
	(footprint ""
		(layer "F.Cu")
		(at 426.884084 -29.222954 -90)
		(property "Reference" "PC969"
			(at 0 0 270)
			(layer "F.SilkS")
			(hide yes)
			(effects
				(font
					(size 1.27 1.27)
				)
			)
		)
		(property "Value" ""
			(at 0 0 270)
			(layer "F.Fab")
			(effects
				(font
					(size 1.27 1.27)
				)
			)
		)
		(duplicate_pad_numbers_are_jumpers no)
		(fp_line
			(start -0.7874 0.4064)
			(end -0.7874 -0.4064)
			(stroke
				(width 0.1524)
				(type default)
			)
			(layer "F.SilkS")
		)
		(fp_line
			(start 0.7874 0.4064)
			(end -0.7874 0.4064)
			(stroke
				(width 0.1524)
				(type default)
			)
			(layer "F.SilkS")
		)
		(fp_line
			(start -0.7874 -0.4064)
			(end 0.7874 -0.4064)
			(stroke
				(width 0.1524)
				(type default)
			)
			(layer "F.SilkS")
		)
		(fp_line
			(start 0.7874 -0.4064)
			(end 0.7874 0.4064)
			(stroke
				(width 0.1524)
				(type default)
			)
			(layer "F.SilkS")
		)
		(fp_line
			(start -0.67945 0.3048)
			(end -0.67945 -0.305054)
			(stroke
				(width 0.1)
				(type default)
			)
			(layer "F.Fab")
		)
		(fp_line
			(start -0.12065 0.3048)
			(end -0.67945 0.3048)
			(stroke
				(width 0.1)
				(type default)
			)
			(layer "F.Fab")
		)
		(fp_line
			(start 0.120396 0.3048)
			(end 0.120396 0.2794)
			(stroke
				(width 0.1)
				(type default)
			)
			(layer "F.Fab")
		)
		(fp_line
			(start 0.67945 0.3048)
			(end 0.120396 0.3048)
			(stroke
				(width 0.1)
				(type default)
			)
			(layer "F.Fab")
		)
		(fp_line
			(start -0.12065 0.2794)
			(end -0.12065 0.3048)
			(stroke
				(width 0.1)
				(type default)
			)
			(layer "F.Fab")
		)
		(fp_line
			(start 0.120396 0.2794)
			(end -0.12065 0.2794)
			(stroke
				(width 0.1)
				(type default)
			)
			(layer "F.Fab")
		)
		(fp_line
			(start -0.12065 -0.2794)
			(end 0.12065 -0.2794)
			(stroke
				(width 0.1)
				(type default)
			)
			(layer "F.Fab")
		)
		(fp_line
			(start 0.12065 -0.2794)
			(end 0.12065 -0.3048)
			(stroke
				(width 0.1)
				(type default)
			)
			(layer "F.Fab")
		)
		(fp_line
			(start 0.12065 -0.3048)
			(end 0.67945 -0.3048)
			(stroke
				(width 0.1)
				(type default)
			)
			(layer "F.Fab")
		)
		(fp_line
			(start 0.67945 -0.3048)
			(end 0.67945 0.3048)
			(stroke
				(width 0.1)
				(type default)
			)
			(layer "F.Fab")
		)
		(fp_line
			(start -0.67945 -0.305054)
			(end -0.12065 -0.305054)
			(stroke
				(width 0.1)
				(type default)
			)
			(layer "F.Fab")
		)
		(fp_line
			(start -0.12065 -0.305054)
			(end -0.12065 -0.2794)
			(stroke
				(width 0.1)
				(type default)
			)
			(layer "F.Fab")
		)
		(pad "1" smd circle
			(at -0.40005 0 270)
			(size 0 0)
			(layers "F.Cu" "F.Mask" "F.Paste")
			(net "P3V3_AUX")
		)
		(pad "2" smd circle
			(at 0.40005 0 270)
			(size 0 0)
			(layers "F.Cu" "F.Mask" "F.Paste")
			(net "GND")
		)
	)
	(footprint ""
		(layer "F.Cu")
		(at 230.682038 -38.041072 180)
		(property "Reference" "R6084"
			(at 0 0 180)
			(layer "F.SilkS")
			(hide yes)
			(effects
				(font
					(size 1.27 1.27)
				)
			)
		)
		(property "Value" ""
			(at 0 0 180)
			(layer "F.Fab")
			(effects
				(font
					(size 1.27 1.27)
				)
			)
		)
		(duplicate_pad_numbers_are_jumpers no)
		(fp_line
			(start 0.7874 0.4064)
			(end -0.7874 0.4064)
			(stroke
				(width 0.1524)
				(type default)
			)
			(layer "F.SilkS")
		)
		(fp_line
			(start 0.7874 -0.4064)
			(end 0.7874 0.4064)
			(stroke
				(width 0.1524)
				(type default)
			)
			(layer "F.SilkS")
		)
		(fp_line
			(start -0.7874 0.4064)
			(end -0.7874 -0.4064)
			(stroke
				(width 0.1524)
				(type default)
			)
			(layer "F.SilkS")
		)
		(fp_line
			(start -0.7874 -0.4064)
			(end 0.7874 -0.4064)
			(stroke
				(width 0.1524)
				(type default)
			)
			(layer "F.SilkS")
		)
		(fp_line
			(start 0.67945 0.3048)
			(end 0.120396 0.3048)
			(stroke
				(width 0.1)
				(type default)
			)
			(layer "F.Fab")
		)
		(fp_line
			(start 0.67945 -0.3048)
			(end 0.67945 0.3048)
			(stroke
				(width 0.1)
				(type default)
			)
			(layer "F.Fab")
		)
		(fp_line
			(start 0.12065 -0.2794)
			(end 0.12065 -0.3048)
			(stroke
				(width 0.1)
				(type default)
			)
			(layer "F.Fab")
		)
		(fp_line
			(start 0.12065 -0.3048)
			(end 0.67945 -0.3048)
			(stroke
				(width 0.1)
				(type default)
			)
			(layer "F.Fab")
		)
		(fp_line
			(start 0.120396 0.3048)
			(end 0.120396 0.2794)
			(stroke
				(width 0.1)
				(type default)
			)
			(layer "F.Fab")
		)
		(fp_line
			(start 0.120396 0.2794)
			(end -0.12065 0.2794)
			(stroke
				(width 0.1)
				(type default)
			)
			(layer "F.Fab")
		)
		(fp_line
			(start -0.12065 0.3048)
			(end -0.67945 0.3048)
			(stroke
				(width 0.1)
				(type default)
			)
			(layer "F.Fab")
		)
		(fp_line
			(start -0.12065 0.2794)
			(end -0.12065 0.3048)
			(stroke
				(width 0.1)
				(type default)
			)
			(layer "F.Fab")
		)
		(fp_line
			(start -0.12065 -0.2794)
			(end 0.12065 -0.2794)
			(stroke
				(width 0.1)
				(type default)
			)
			(layer "F.Fab")
		)
		(fp_line
			(start -0.12065 -0.305054)
			(end -0.12065 -0.2794)
			(stroke
				(width 0.1)
				(type default)
			)
			(layer "F.Fab")
		)
		(fp_line
			(start -0.67945 0.3048)
			(end -0.67945 -0.305054)
			(stroke
				(width 0.1)
				(type default)
			)
			(layer "F.Fab")
		)
		(fp_line
			(start -0.67945 -0.305054)
			(end -0.12065 -0.305054)
			(stroke
				(width 0.1)
				(type default)
			)
			(layer "F.Fab")
		)
		(pad "1" smd circle
			(at -0.40005 0 180)
			(size 0 0)
			(layers "F.Cu" "F.Mask" "F.Paste")
			(net "P5V_AUX")
		)
		(pad "2" smd circle
			(at 0.40005 0 180)
			(size 0 0)
			(layers "F.Cu" "F.Mask" "F.Paste")
			(net "P3V3_SSD8_PG_G2")
		)
	)
)
